# T6G (Grand Teton) — schematic netlist excerpt (pin names and nets, part order shuffled) for the footprints in the layout excerpt that follows; sources: Cadence DE-HDL packaged netlist, KiCad conversion of 04192023_DAF0TMB3IC0_F0TG_MB_C_brd_V02_OCP.brd

R3496  Q_RES  33.2 1% CHIP  pkg 0402LF  page 129 : A = GPU_FPGA_EROT_RST_BUF_R_N ; B = GPU_FPGA_EROT_RST_BUF_N
PR4006  Q_RES  100 1% EMPTY  pkg 0402LF  page 152 : A = P12V_SCM_R ; B = P12V_SCM_AVIN_PD

(kicad_pcb
	(version 20260206)
	(generator "pcbnew")
	(generator_version "10.0")
	(general
		(thickness 1.6)
		(legacy_teardrops no)
	)
	(paper "A4")
	(title_block
		(title "04192023_DAF0TMB3IC0_F0TG_MB_C_brd_V02_OCP.brd")
		(comment 1 "Grand Teton / footprints 4245-4246 of 8354")
	)
	(layers
		(0 "F.Cu" signal "TOP")
		(4 "In1.Cu" signal "GND")
		(6 "In2.Cu" signal "IN1")
		(8 "In3.Cu" signal "GND1")
		(10 "In4.Cu" signal "IN2")
		(12 "In5.Cu" signal "GND2")
		(14 "In6.Cu" signal "IN3")
		(16 "In7.Cu" signal "GND3")
		(18 "In8.Cu" signal "VCC")
		(20 "In9.Cu" signal "VCC1")
		(22 "In10.Cu" signal "GND4")
		(24 "In11.Cu" signal "IN4")
		(26 "In12.Cu" signal "GND5")
		(28 "In13.Cu" signal "IN5")
		(30 "In14.Cu" signal "GND6")
		(32 "In15.Cu" signal "IN6")
		(34 "In16.Cu" signal "GND7")
		(2 "B.Cu" signal "BOTTOM")
		(9 "F.Adhes" user "F.Adhesive")
		(11 "B.Adhes" user "B.Adhesive")
		(13 "F.Paste" user "Package Geometry/Pastemask Top")
		(15 "B.Paste" user "Package Geometry/Pastemask Bottom")
		(5 "F.SilkS" user "Ref Des/Silkscreen Top")
		(7 "B.SilkS" user "Ref Des/Silkscreen Bottom")
		(1 "F.Mask" user "Board Geometry/Soldermask Top")
		(3 "B.Mask" user "Board Geometry/Soldermask Bottom")
		(17 "Dwgs.User" user "User.Drawings")
		(19 "Cmts.User" user "User.Comments")
		(21 "Eco1.User" user "User.Eco1")
		(23 "Eco2.User" user "User.Eco2")
		(25 "Edge.Cuts" user "Board Geometry/Outline")
		(27 "Margin" user)
		(31 "F.CrtYd" user "Package Geometry/Place Bound Top")
		(29 "B.CrtYd" user "Package Geometry/Place Bound Bottom")
		(35 "F.Fab" user "Ref Des/Assembly Top")
		(33 "B.Fab" user "Ref Des/Assembly Bottom")
	)
	(footprint ""
		(layer "F.Cu")
		(at 103.505 -417.957)
		(property "Reference" "R3496"
			(at 0 0 0)
			(layer "F.SilkS")
			(hide yes)
			(effects
				(font
					(size 1.27 1.27)
				)
			)
		)
		(property "Value" ""
			(at 0 0 0)
			(layer "F.Fab")
			(effects
				(font
					(size 1.27 1.27)
				)
			)
		)
		(duplicate_pad_numbers_are_jumpers no)
		(fp_line
			(start -0.7874 -0.4064)
			(end 0.7874 -0.4064)
			(stroke
				(width 0.1524)
				(type default)
			)
			(layer "F.SilkS")
		)
		(fp_line
			(start -0.7874 0.4064)
			(end -0.7874 -0.4064)
			(stroke
				(width 0.1524)
				(type default)
			)
			(layer "F.SilkS")
		)
		(fp_line
			(start 0.7874 -0.4064)
			(end 0.7874 0.4064)
			(stroke
				(width 0.1524)
				(type default)
			)
			(layer "F.SilkS")
		)
		(fp_line
			(start 0.7874 0.4064)
			(end -0.7874 0.4064)
			(stroke
				(width 0.1524)
				(type default)
			)
			(layer "F.SilkS")
		)
		(fp_line
			(start -0.67945 -0.305054)
			(end -0.12065 -0.305054)
			(stroke
				(width 0.1)
				(type default)
			)
			(layer "F.Fab")
		)
		(fp_line
			(start -0.67945 0.3048)
			(end -0.67945 -0.305054)
			(stroke
				(width 0.1)
				(type default)
			)
			(layer "F.Fab")
		)
		(fp_line
			(start -0.12065 -0.305054)
			(end -0.12065 -0.2794)
			(stroke
				(width 0.1)
				(type default)
			)
			(layer "F.Fab")
		)
		(fp_line
			(start -0.12065 -0.2794)
			(end 0.12065 -0.2794)
			(stroke
				(width 0.1)
				(type default)
			)
			(layer "F.Fab")
		)
		(fp_line
			(start -0.12065 0.2794)
			(end -0.12065 0.3048)
			(stroke
				(width 0.1)
				(type default)
			)
			(layer "F.Fab")
		)
		(fp_line
			(start -0.12065 0.3048)
			(end -0.67945 0.3048)
			(stroke
				(width 0.1)
				(type default)
			)
			(layer "F.Fab")
		)
		(fp_line
			(start 0.120396 0.2794)
			(end -0.12065 0.2794)
			(stroke
				(width 0.1)
				(type default)
			)
			(layer "F.Fab")
		)
		(fp_line
			(start 0.120396 0.3048)
			(end 0.120396 0.2794)
			(stroke
				(width 0.1)
				(type default)
			)
			(layer "F.Fab")
		)
		(fp_line
			(start 0.12065 -0.3048)
			(end 0.67945 -0.3048)
			(stroke
				(width 0.1)
				(type default)
			)
			(layer "F.Fab")
		)
		(fp_line
			(start 0.12065 -0.2794)
			(end 0.12065 -0.3048)
			(stroke
				(width 0.1)
				(type default)
			)
			(layer "F.Fab")
		)
		(fp_line
			(start 0.67945 -0.3048)
			(end 0.67945 0.3048)
			(stroke
				(width 0.1)
				(type default)
			)
			(layer "F.Fab")
		)
		(fp_line
			(start 0.67945 0.3048)
			(end 0.120396 0.3048)
			(stroke
				(width 0.1)
				(type default)
			)
			(layer "F.Fab")
		)
		(pad "1" smd circle
			(at -0.40005 0)
			(size 0 0)
			(layers "F.Cu" "F.Mask" "F.Paste")
			(net "GPU_FPGA_EROT_RST_BUF_R_N")
		)
		(pad "2" smd circle
			(at 0.40005 0)
			(size 0 0)
			(layers "F.Cu" "F.Mask" "F.Paste")
			(net "GPU_FPGA_EROT_RST_BUF_N")
		)
	)
	(footprint ""
		(layer "F.Cu")
		(at 175.883062 -23.283672 180)
		(property "Reference" "PR4006"
			(at 0 0 180)
			(layer "F.SilkS")
			(hide yes)
			(effects
				(font
					(size 1.27 1.27)
				)
			)
		)
		(property "Value" ""
			(at 0 0 180)
			(layer "F.Fab")
			(effects
				(font
					(size 1.27 1.27)
				)
			)
		)
		(duplicate_pad_numbers_are_jumpers no)
		(fp_line
			(start 0.7874 0.4064)
			(end -0.7874 0.4064)
			(stroke
				(width 0.1524)
				(type default)
			)
			(layer "F.SilkS")
		)
		(fp_line
			(start 0.7874 -0.4064)
			(end 0.7874 0.4064)
			(stroke
				(width 0.1524)
				(type default)
			)
			(layer "F.SilkS")
		)
		(fp_line
			(start -0.7874 0.4064)
			(end -0.7874 -0.4064)
			(stroke
				(width 0.1524)
				(type default)
			)
			(layer "F.SilkS")
		)
		(fp_line
			(start -0.7874 -0.4064)
			(end 0.7874 -0.4064)
			(stroke
				(width 0.1524)
				(type default)
			)
			(layer "F.SilkS")
		)
		(fp_line
			(start 0.67945 0.3048)
			(end 0.120396 0.3048)
			(stroke
				(width 0.1)
				(type default)
			)
			(layer "F.Fab")
		)
		(fp_line
			(start 0.67945 -0.3048)
			(end 0.67945 0.3048)
			(stroke
				(width 0.1)
				(type default)
			)
			(layer "F.Fab")
		)
		(fp_line
			(start 0.12065 -0.2794)
			(end 0.12065 -0.3048)
			(stroke
				(width 0.1)
				(type default)
			)
			(layer "F.Fab")
		)
		(fp_line
			(start 0.12065 -0.3048)
			(end 0.67945 -0.3048)
			(stroke
				(width 0.1)
				(type default)
			)
			(layer "F.Fab")
		)
		(fp_line
			(start 0.120396 0.3048)
			(end 0.120396 0.2794)
			(stroke
				(width 0.1)
				(type default)
			)
			(layer "F.Fab")
		)
		(fp_line
			(start 0.120396 0.2794)
			(end -0.12065 0.2794)
			(stroke
				(width 0.1)
				(type default)
			)
			(layer "F.Fab")
		)
		(fp_line
			(start -0.12065 0.3048)
			(end -0.67945 0.3048)
			(stroke
				(width 0.1)
				(type default)
			)
			(layer "F.Fab")
		)
		(fp_line
			(start -0.12065 0.2794)
			(end -0.12065 0.3048)
			(stroke
				(width 0.1)
				(type default)
			)
			(layer "F.Fab")
		)
		(fp_line
			(start -0.12065 -0.2794)
			(end 0.12065 -0.2794)
			(stroke
				(width 0.1)
				(type default)
			)
			(layer "F.Fab")
		)
		(fp_line
			(start -0.12065 -0.305054)
			(end -0.12065 -0.2794)
			(stroke
				(width 0.1)
				(type default)
			)
			(layer "F.Fab")
		)
		(fp_line
			(start -0.67945 0.3048)
			(end -0.67945 -0.305054)
			(stroke
				(width 0.1)
				(type default)
			)
			(layer "F.Fab")
		)
		(fp_line
			(start -0.67945 -0.305054)
			(end -0.12065 -0.305054)
			(stroke
				(width 0.1)
				(type default)
			)
			(layer "F.Fab")
		)
		(pad "1" smd circle
			(at -0.40005 0 180)
			(size 0 0)
			(layers "F.Cu" "F.Mask" "F.Paste")
			(net "P12V_SCM_R")
		)
		(pad "2" smd circle
			(at 0.40005 0 180)
			(size 0 0)
			(layers "F.Cu" "F.Mask" "F.Paste")
			(net "P12V_SCM_AVIN_PD")
		)
	)
)
